#ISCELL
  pure_quanta quanta_title_block_c *
  *
#ISCELL
  pure_quanta_power cad_note *
  *
#CELL
  pure_quanta genoa_sp5 *
  page45_i159
#ISCELL
  mstr_standard offpage *
  page45_i160
#ISCELL
  mstr_standard offpage *
  page45_i161
#ISCELL
  mstr_standard tap *
  page45_i162
#ISCELL
  mstr_standard tap *
  page45_i163
#ISCELL
  mstr_standard tap *
  page45_i164
#ISCELL
  mstr_standard tap *
  page45_i165
#ISCELL
  mstr_standard tap *
  page45_i166
#ISCELL
  mstr_standard tap *
  page45_i167
#ISCELL
  mstr_standard tap *
  page45_i168
#ISCELL
  mstr_standard tap *
  page45_i169
#ISCELL
  mstr_standard tap *
  page45_i170
#ISCELL
  mstr_standard tap *
  page45_i171
#ISCELL
  mstr_standard tap *
  page45_i172
#ISCELL
  mstr_standard tap *
  page45_i173
#ISCELL
  mstr_standard tap *
  page45_i174
#ISCELL
  mstr_standard tap *
  page45_i175
#ISCELL
  mstr_standard tap *
  page45_i176
#ISCELL
  mstr_standard tap *
  page45_i177
#ISCELL
  mstr_standard tap *
  page45_i178
#ISCELL
  mstr_standard tap *
  page45_i179
#ISCELL
  mstr_standard tap *
  page45_i180
#ISCELL
  mstr_standard tap *
  page45_i181
#ISCELL
  mstr_standard tap *
  page45_i182
#ISCELL
  mstr_standard tap *
  page45_i183
#ISCELL
  mstr_standard tap *
  page45_i184
#ISCELL
  mstr_standard tap *
  page45_i185
#ISCELL
  mstr_standard tap *
  page45_i186
#ISCELL
  mstr_standard tap *
  page45_i187
#ISCELL
  mstr_standard tap *
  page45_i188
#ISCELL
  mstr_standard tap *
  page45_i189
#ISCELL
  mstr_standard tap *
  page45_i190
#ISCELL
  mstr_standard tap *
  page45_i191
#ISCELL
  mstr_standard tap *
  page45_i192
#ISCELL
  mstr_standard tap *
  page45_i193
#ISCELL
  mstr_standard tap *
  page45_i194
#ISCELL
  mstr_standard tap *
  page45_i195
#ISCELL
  mstr_standard offpage *
  page45_i196
#ISCELL
  mstr_standard tap *
  page45_i197
#ISCELL
  mstr_standard tap *
  page45_i198
#ISCELL
  mstr_standard tap *
  page45_i199
#ISCELL
  mstr_standard tap *
  page45_i200
#ISCELL
  mstr_standard tap *
  page45_i201
#ISCELL
  mstr_standard tap *
  page45_i202
#ISCELL
  mstr_standard tap *
  page45_i203
#ISCELL
  mstr_standard tap *
  page45_i204
#ISCELL
  mstr_standard tap *
  page45_i205
#ISCELL
  mstr_standard tap *
  page45_i206
#ISCELL
  mstr_standard tap *
  page45_i207
#ISCELL
  mstr_standard tap *
  page45_i208
#ISCELL
  mstr_standard tap *
  page45_i209
#ISCELL
  mstr_standard tap *
  page45_i210
#ISCELL
  mstr_standard tap *
  page45_i211
#ISCELL
  mstr_standard tap *
  page45_i212
#ISCELL
  mstr_standard tap *
  page45_i213
#ISCELL
  mstr_standard tap *
  page45_i214
#ISCELL
  mstr_standard tap *
  page45_i215
#ISCELL
  mstr_standard tap *
  page45_i216
#ISCELL
  mstr_standard tap *
  page45_i217
#ISCELL
  mstr_standard tap *
  page45_i218
#ISCELL
  mstr_standard tap *
  page45_i219
#ISCELL
  mstr_standard tap *
  page45_i220
#ISCELL
  mstr_standard tap *
  page45_i221
#ISCELL
  mstr_standard tap *
  page45_i222
#ISCELL
  mstr_standard tap *
  page45_i223
#ISCELL
  mstr_standard tap *
  page45_i224
#ISCELL
  mstr_standard tap *
  page45_i225
#ISCELL
  mstr_standard tap *
  page45_i226
#ISCELL
  mstr_standard tap *
  page45_i227
#ISCELL
  mstr_standard tap *
  page45_i228
#ISCELL
  mstr_standard tap *
  page45_i229
#ISCELL
  mstr_standard tap *
  page45_i230
#ISCELL
  mstr_standard tap *
  page45_i231
#ISCELL
  mstr_standard tap *
  page45_i232
#ISCELL
  mstr_standard tap *
  page45_i233
#ISCELL
  mstr_standard offpage *
  page45_i234
#ISCELL
  mstr_standard tap *
  page45_i235
#ISCELL
  mstr_standard tap *
  page45_i236
#ISCELL
  mstr_standard tap *
  page45_i237
#ISCELL
  mstr_standard tap *
  page45_i238
#ISCELL
  mstr_standard tap *
  page45_i239
#ISCELL
  mstr_standard tap *
  page45_i240
#ISCELL
  mstr_standard tap *
  page45_i241
#ISCELL
  mstr_standard tap *
  page45_i242
#ISCELL
  mstr_standard tap *
  page45_i243
#ISCELL
  mstr_standard tap *
  page45_i244
#ISCELL
  mstr_standard tap *
  page45_i245
#ISCELL
  mstr_standard tap *
  page45_i246
#ISCELL
  mstr_standard tap *
  page45_i247
#ISCELL
  mstr_standard tap *
  page45_i248
#ISCELL
  mstr_standard tap *
  page45_i249
#ISCELL
  mstr_standard tap *
  page45_i250
#ISCELL
  mstr_standard tap *
  page45_i251
#ISCELL
  mstr_standard tap *
  page45_i252
#ISCELL
  mstr_standard tap *
  page45_i253
#ISCELL
  mstr_standard tap *
  page45_i254
#ISCELL
  mstr_standard tap *
  page45_i255
#ISCELL
  mstr_standard tap *
  page45_i256
#ISCELL
  mstr_standard tap *
  page45_i257
#ISCELL
  mstr_standard tap *
  page45_i258
#ISCELL
  mstr_standard tap *
  page45_i259
#ISCELL
  mstr_standard tap *
  page45_i260
#ISCELL
  mstr_standard tap *
  page45_i261
#ISCELL
  mstr_standard tap *
  page45_i262
#ISCELL
  mstr_standard tap *
  page45_i263
#ISCELL
  mstr_standard tap *
  page45_i264
#ISCELL
  mstr_standard tap *
  page45_i265
#ISCELL
  mstr_standard tap *
  page45_i266
#ISCELL
  mstr_standard tap *
  page45_i267
#ISCELL
  mstr_standard tap *
  page45_i268
#ISCELL
  mstr_standard tap *
  page45_i269
#ISCELL
  mstr_standard tap *
  page45_i270
#ISCELL
  mstr_standard tap *
  page45_i271
#ISCELL
  mstr_standard tap *
  page45_i272
#ISCELL
  mstr_standard tap *
  page45_i273
#ISCELL
  mstr_standard tap *
  page45_i274
#ISCELL
  mstr_standard tap *
  page45_i275
#ISCELL
  mstr_standard tap *
  page45_i276
#ISCELL
  mstr_standard tap *
  page45_i277
#ISCELL
  mstr_standard tap *
  page45_i278
#ISCELL
  mstr_standard tap *
  page45_i279
#ISCELL
  mstr_standard tap *
  page45_i280
#ISCELL
  standard offpage *
  page45_i281
#ISCELL
  standard offpage *
  page45_i282
#ISCELL
  standard offpage *
  page45_i283
#ISCELL
  standard offpage *
  page45_i284
#ISCELL
  mstr_standard tap *
  page45_i285
#ISCELL
  mstr_standard tap *
  page45_i286
#ISCELL
  mstr_standard tap *
  page45_i287
#ISCELL
  mstr_standard tap *
  page45_i288
#ISCELL
  mstr_standard tap *
  page45_i289
#ISCELL
  mstr_standard tap *
  page45_i290
#ISCELL
  mstr_standard tap *
  page45_i291
#ISCELL
  mstr_standard tap *
  page45_i292
#ISCELL
  mstr_standard tap *
  page45_i293
#ISCELL
  mstr_standard tap *
  page45_i294
#ISCELL
  mstr_standard tap *
  page45_i295
#ISCELL
  mstr_standard tap *
  page45_i296
#ISCELL
  mstr_standard tap *
  page45_i297
#ISCELL
  mstr_standard tap *
  page45_i298
#ISCELL
  mstr_standard tap *
  page45_i299
#ISCELL
  mstr_standard tap *
  page45_i300
#ISCELL
  mstr_standard tap *
  page45_i301
#ISCELL
  standard offpage *
  page45_i302
#ISCELL
  standard offpage *
  page45_i303
#ISCELL
  standard offpage *
  page45_i304
#ISCELL
  standard offpage *
  page45_i305
#ISCELL
  standard offpage *
  page45_i306
#ISCELL
  standard offpage *
  page45_i307
#ISCELL
  standard offpage *
  page45_i308
#ISCELL
  mstr_standard offpage *
  page45_i309
#ISCELL
  standard offpage *
  page45_i310
#ISCELL
  standard offpage *
  page45_i311
#ISCELL
  standard offpage *
  page45_i312
#ISCELL
  standard offpage *
  page45_i313
#CELL
  pure_quanta q_res *
  page45_i314
#ISCELL
  mstr_standard offpage *
  page45_i315
#ISCELL
  standard offpage *
  page45_i316
